# T6G (Grand Teton) — schematic netlist excerpt (pin names and nets, part order shuffled) for the footprints in the layout excerpt that follows; sources: Cadence DE-HDL packaged netlist, KiCad conversion of 04192023_DAF0TMB3IC0_F0TG_MB_C_brd_V02_OCP.brd

C6706  Q_CAP_DIFFBUS  DIFF BUS_0.22UF 6.3V 20% X6S  pkg C0201  page 341 : \1\ = P5E_CPU1_P2_TX_BUF_C_DN<6> ; \2\ = P5E_CPU1_P2_TX_BUF_DN<6>
R3955  Q_RES  0 5% CHIP  pkg 0402LF  page 147 : A = P12V_E1S_IMON_0 ; B = P12V_E1S_0_ISENSE_MPS_MAM
R6276  Q_RES  0 5% CHIP  pkg 0402LF  page 179 : A = USB_HUB2_TI_VDD33_MRP_PRT_CTL4_GANGPWR ; B = USB_HUB2_MRP_PRT_CTL4_GANGPWR

(kicad_pcb
	(version 20260206)
	(generator "pcbnew")
	(generator_version "10.0")
	(general
		(thickness 1.6)
		(legacy_teardrops no)
	)
	(paper "A4")
	(title_block
		(title "04192023_DAF0TMB3IC0_F0TG_MB_C_brd_V02_OCP.brd")
		(comment 1 "Grand Teton / footprints 4076-4078 of 8354")
	)
	(layers
		(0 "F.Cu" signal "TOP")
		(4 "In1.Cu" signal "GND")
		(6 "In2.Cu" signal "IN1")
		(8 "In3.Cu" signal "GND1")
		(10 "In4.Cu" signal "IN2")
		(12 "In5.Cu" signal "GND2")
		(14 "In6.Cu" signal "IN3")
		(16 "In7.Cu" signal "GND3")
		(18 "In8.Cu" signal "VCC")
		(20 "In9.Cu" signal "VCC1")
		(22 "In10.Cu" signal "GND4")
		(24 "In11.Cu" signal "IN4")
		(26 "In12.Cu" signal "GND5")
		(28 "In13.Cu" signal "IN5")
		(30 "In14.Cu" signal "GND6")
		(32 "In15.Cu" signal "IN6")
		(34 "In16.Cu" signal "GND7")
		(2 "B.Cu" signal "BOTTOM")
		(9 "F.Adhes" user "F.Adhesive")
		(11 "B.Adhes" user "B.Adhesive")
		(13 "F.Paste" user "Package Geometry/Pastemask Top")
		(15 "B.Paste" user "Package Geometry/Pastemask Bottom")
		(5 "F.SilkS" user "Ref Des/Silkscreen Top")
		(7 "B.SilkS" user "Ref Des/Silkscreen Bottom")
		(1 "F.Mask" user "Board Geometry/Soldermask Top")
		(3 "B.Mask" user "Board Geometry/Soldermask Bottom")
		(17 "Dwgs.User" user "User.Drawings")
		(19 "Cmts.User" user "User.Comments")
		(21 "Eco1.User" user "User.Eco1")
		(23 "Eco2.User" user "User.Eco2")
		(25 "Edge.Cuts" user "Board Geometry/Outline")
		(27 "Margin" user)
		(31 "F.CrtYd" user "Package Geometry/Place Bound Top")
		(29 "B.CrtYd" user "Package Geometry/Place Bound Bottom")
		(35 "F.Fab" user "Ref Des/Assembly Top")
		(33 "B.Fab" user "Ref Des/Assembly Bottom")
	)
	(footprint ""
		(layer "F.Cu")
		(at 257.85953 -57.511442)
		(property "Reference" "R3955"
			(at 0 0 0)
			(layer "F.SilkS")
			(hide yes)
			(effects
				(font
					(size 1.27 1.27)
				)
			)
		)
		(property "Value" ""
			(at 0 0 0)
			(layer "F.Fab")
			(effects
				(font
					(size 1.27 1.27)
				)
			)
		)
		(duplicate_pad_numbers_are_jumpers no)
		(fp_line
			(start -0.7874 -0.4064)
			(end 0.7874 -0.4064)
			(stroke
				(width 0.1524)
				(type default)
			)
			(layer "F.SilkS")
		)
		(fp_line
			(start -0.7874 0.4064)
			(end -0.7874 -0.4064)
			(stroke
				(width 0.1524)
				(type default)
			)
			(layer "F.SilkS")
		)
		(fp_line
			(start 0.7874 -0.4064)
			(end 0.7874 0.4064)
			(stroke
				(width 0.1524)
				(type default)
			)
			(layer "F.SilkS")
		)
		(fp_line
			(start 0.7874 0.4064)
			(end -0.7874 0.4064)
			(stroke
				(width 0.1524)
				(type default)
			)
			(layer "F.SilkS")
		)
		(fp_line
			(start -0.67945 -0.305054)
			(end -0.12065 -0.305054)
			(stroke
				(width 0.1)
				(type default)
			)
			(layer "F.Fab")
		)
		(fp_line
			(start -0.67945 0.3048)
			(end -0.67945 -0.305054)
			(stroke
				(width 0.1)
				(type default)
			)
			(layer "F.Fab")
		)
		(fp_line
			(start -0.12065 -0.305054)
			(end -0.12065 -0.2794)
			(stroke
				(width 0.1)
				(type default)
			)
			(layer "F.Fab")
		)
		(fp_line
			(start -0.12065 -0.2794)
			(end 0.12065 -0.2794)
			(stroke
				(width 0.1)
				(type default)
			)
			(layer "F.Fab")
		)
		(fp_line
			(start -0.12065 0.2794)
			(end -0.12065 0.3048)
			(stroke
				(width 0.1)
				(type default)
			)
			(layer "F.Fab")
		)
		(fp_line
			(start -0.12065 0.3048)
			(end -0.67945 0.3048)
			(stroke
				(width 0.1)
				(type default)
			)
			(layer "F.Fab")
		)
		(fp_line
			(start 0.120396 0.2794)
			(end -0.12065 0.2794)
			(stroke
				(width 0.1)
				(type default)
			)
			(layer "F.Fab")
		)
		(fp_line
			(start 0.120396 0.3048)
			(end 0.120396 0.2794)
			(stroke
				(width 0.1)
				(type default)
			)
			(layer "F.Fab")
		)
		(fp_line
			(start 0.12065 -0.3048)
			(end 0.67945 -0.3048)
			(stroke
				(width 0.1)
				(type default)
			)
			(layer "F.Fab")
		)
		(fp_line
			(start 0.12065 -0.2794)
			(end 0.12065 -0.3048)
			(stroke
				(width 0.1)
				(type default)
			)
			(layer "F.Fab")
		)
		(fp_line
			(start 0.67945 -0.3048)
			(end 0.67945 0.3048)
			(stroke
				(width 0.1)
				(type default)
			)
			(layer "F.Fab")
		)
		(fp_line
			(start 0.67945 0.3048)
			(end 0.120396 0.3048)
			(stroke
				(width 0.1)
				(type default)
			)
			(layer "F.Fab")
		)
		(pad "1" smd circle
			(at -0.40005 0)
			(size 0 0)
			(layers "F.Cu" "F.Mask" "F.Paste")
			(net "P12V_E1S_IMON_0")
		)
		(pad "2" smd circle
			(at 0.40005 0)
			(size 0 0)
			(layers "F.Cu" "F.Mask" "F.Paste")
			(net "P12V_E1S_0_ISENSE_MPS_MAM")
		)
	)
	(footprint ""
		(layer "F.Cu")
		(at 123.443238 -41.17975 90)
		(property "Reference" "R6276"
			(at 0 0 90)
			(layer "F.SilkS")
			(hide yes)
			(effects
				(font
					(size 1.27 1.27)
				)
			)
		)
		(property "Value" ""
			(at 0 0 90)
			(layer "F.Fab")
			(effects
				(font
					(size 1.27 1.27)
				)
			)
		)
		(duplicate_pad_numbers_are_jumpers no)
		(fp_line
			(start 0.7874 -0.4064)
			(end 0.7874 0.4064)
			(stroke
				(width 0.1524)
				(type default)
			)
			(layer "F.SilkS")
		)
		(fp_line
			(start -0.7874 -0.4064)
			(end 0.7874 -0.4064)
			(stroke
				(width 0.1524)
				(type default)
			)
			(layer "F.SilkS")
		)
		(fp_line
			(start 0.7874 0.4064)
			(end -0.7874 0.4064)
			(stroke
				(width 0.1524)
				(type default)
			)
			(layer "F.SilkS")
		)
		(fp_line
			(start -0.7874 0.4064)
			(end -0.7874 -0.4064)
			(stroke
				(width 0.1524)
				(type default)
			)
			(layer "F.SilkS")
		)
		(fp_line
			(start -0.12065 -0.305054)
			(end -0.12065 -0.2794)
			(stroke
				(width 0.1)
				(type default)
			)
			(layer "F.Fab")
		)
		(fp_line
			(start -0.67945 -0.305054)
			(end -0.12065 -0.305054)
			(stroke
				(width 0.1)
				(type default)
			)
			(layer "F.Fab")
		)
		(fp_line
			(start 0.67945 -0.3048)
			(end 0.67945 0.3048)
			(stroke
				(width 0.1)
				(type default)
			)
			(layer "F.Fab")
		)
		(fp_line
			(start 0.12065 -0.3048)
			(end 0.67945 -0.3048)
			(stroke
				(width 0.1)
				(type default)
			)
			(layer "F.Fab")
		)
		(fp_line
			(start 0.12065 -0.2794)
			(end 0.12065 -0.3048)
			(stroke
				(width 0.1)
				(type default)
			)
			(layer "F.Fab")
		)
		(fp_line
			(start -0.12065 -0.2794)
			(end 0.12065 -0.2794)
			(stroke
				(width 0.1)
				(type default)
			)
			(layer "F.Fab")
		)
		(fp_line
			(start 0.120396 0.2794)
			(end -0.12065 0.2794)
			(stroke
				(width 0.1)
				(type default)
			)
			(layer "F.Fab")
		)
		(fp_line
			(start -0.12065 0.2794)
			(end -0.12065 0.3048)
			(stroke
				(width 0.1)
				(type default)
			)
			(layer "F.Fab")
		)
		(fp_line
			(start 0.67945 0.3048)
			(end 0.120396 0.3048)
			(stroke
				(width 0.1)
				(type default)
			)
			(layer "F.Fab")
		)
		(fp_line
			(start 0.120396 0.3048)
			(end 0.120396 0.2794)
			(stroke
				(width 0.1)
				(type default)
			)
			(layer "F.Fab")
		)
		(fp_line
			(start -0.12065 0.3048)
			(end -0.67945 0.3048)
			(stroke
				(width 0.1)
				(type default)
			)
			(layer "F.Fab")
		)
		(fp_line
			(start -0.67945 0.3048)
			(end -0.67945 -0.305054)
			(stroke
				(width 0.1)
				(type default)
			)
			(layer "F.Fab")
		)
		(pad "1" smd circle
			(at -0.40005 0 90)
			(size 0 0)
			(layers "F.Cu" "F.Mask" "F.Paste")
			(net "USB_HUB2_TI_VDD33_MRP_PRT_CTL4_GANGPWR")
		)
		(pad "2" smd circle
			(at 0.40005 0 90)
			(size 0 0)
			(layers "F.Cu" "F.Mask" "F.Paste")
			(net "USB_HUB2_MRP_PRT_CTL4_GANGPWR")
		)
	)
	(footprint ""
		(layer "F.Cu")
		(at 133.248146 -408.517344 -90)
		(property "Reference" "C6706"
			(at 0 0 270)
			(layer "F.SilkS")
			(hide yes)
			(effects
				(font
					(size 1.27 1.27)
				)
			)
		)
		(property "Value" ""
			(at 0 0 270)
			(layer "F.Fab")
			(effects
				(font
					(size 1.27 1.27)
				)
			)
		)
		(duplicate_pad_numbers_are_jumpers no)
		(fp_line
			(start -0.299974 0.150114)
			(end -0.299974 -0.150114)
			(stroke
				(width 0.1)
				(type default)
			)
			(layer "F.Fab")
		)
		(fp_line
			(start 0.299974 0.150114)
			(end -0.299974 0.150114)
			(stroke
				(width 0.1)
				(type default)
			)
			(layer "F.Fab")
		)
		(fp_line
			(start -0.299974 -0.150114)
			(end 0.299974 -0.150114)
			(stroke
				(width 0.1)
				(type default)
			)
			(layer "F.Fab")
		)
		(fp_line
			(start 0.299974 -0.150114)
			(end 0.299974 0.150114)
			(stroke
				(width 0.1)
				(type default)
			)
			(layer "F.Fab")
		)
		(pad "1" smd rect
			(at -0.2667 0 270)
			(size 0.3048 0.381)
			(layers "F.Cu" "F.Mask" "F.Paste")
			(net "P5E_CPU1_P2_TX_BUF_C_DN<6>")
		)
		(pad "2" smd rect
			(at 0.2667 0 270)
			(size 0.3048 0.381)
			(layers "F.Cu" "F.Mask" "F.Paste")
			(net "P5E_CPU1_P2_TX_BUF_DN<6>")
		)
	)
)
